# BASEBOARD_FAB2 (Tioga Pass) — schematic netlist excerpt (pin names and nets, part order shuffled) for the footprints in the layout excerpt that follows; sources: Cadence DE-HDL packaged netlist, KiCad conversion of Wiwynn_Tioga_Pass_MB.brd

R7E6  RES  10.0K 1% CHIP  pkg 0402  page 192 : A = P3V3_STBY ; B = PU_RST_PERST_BIT1
R1T35  RES  0.0 5% EMPTY  pkg 0402  page 93 : A = FM_CPU0_PROCHOT_LVT3_N ; B = FM_CPU0_PROCHOT_PCH_N
R4G15  RES  33.2 1% CHIP  pkg 0402  page 229 : A = PWRGD_PVTT_GHJ_CPU1_R ; B = PWRGD_PVTT_CPU1

(kicad_pcb
	(version 20260206)
	(generator "pcbnew")
	(generator_version "10.0")
	(general
		(thickness 1.6)
		(legacy_teardrops no)
	)
	(paper "A4")
	(title_block
		(title "Wiwynn_Tioga_Pass_MB.brd")
		(comment 1 "Tioga Pass / footprints 454-456 of 4770")
	)
	(layers
		(0 "F.Cu" signal "TOP")
		(4 "In1.Cu" signal "L2GND")
		(6 "In2.Cu" signal "L3")
		(8 "In3.Cu" signal "L4GND")
		(10 "In4.Cu" signal "L5")
		(12 "In5.Cu" signal "L6GND")
		(14 "In6.Cu" signal "L7VCC")
		(16 "In7.Cu" signal "L8VCC")
		(18 "In8.Cu" signal "L9GND")
		(20 "In9.Cu" signal "L10")
		(22 "In10.Cu" signal "L11GND")
		(24 "In11.Cu" signal "L12")
		(26 "In12.Cu" signal "L13GND")
		(2 "B.Cu" signal "BOTTOM")
		(9 "F.Adhes" user "F.Adhesive")
		(11 "B.Adhes" user "B.Adhesive")
		(13 "F.Paste" user "Package Geometry/Pastemask Top")
		(15 "B.Paste" user "Package Geometry/Pastemask Bottom")
		(5 "F.SilkS" user "Ref Des/Silkscreen Top")
		(7 "B.SilkS" user "Ref Des/Silkscreen Bottom")
		(1 "F.Mask" user "Board Geometry/Soldermask Top")
		(3 "B.Mask" user "Board Geometry/Soldermask Bottom")
		(17 "Dwgs.User" user "User.Drawings")
		(19 "Cmts.User" user "User.Comments")
		(21 "Eco1.User" user "User.Eco1")
		(23 "Eco2.User" user "User.Eco2")
		(25 "Edge.Cuts" user "Board Geometry/Outline")
		(27 "Margin" user)
		(31 "F.CrtYd" user "Package Geometry/Place Bound Top")
		(29 "B.CrtYd" user "Package Geometry/Place Bound Bottom")
		(35 "F.Fab" user "Ref Des/Assembly Top")
		(33 "B.Fab" user "Ref Des/Assembly Bottom")
	)
	(footprint ""
		(layer "F.Cu")
		(at 370.111274 -64.113664 90)
		(property "Reference" "R7E6"
			(at 0 0 90)
			(layer "F.SilkS")
			(hide yes)
			(effects
				(font
					(size 1.27 1.27)
				)
			)
		)
		(property "Value" ""
			(at 0 0 90)
			(layer "F.Fab")
			(effects
				(font
					(size 1.27 1.27)
				)
			)
		)
		(duplicate_pad_numbers_are_jumpers no)
		(fp_poly
			(pts
				(xy -0.2794 -0.1016) (xy 0.2794 -0.1016) (xy 0.2794 0.9906) (xy -0.2794 0.9906)
			)
			(stroke
				(width 0)
				(type default)
			)
			(fill no)
			(layer "F.CrtYd")
		)
		(fp_line
			(start 0.2794 -0.1016)
			(end -0.2794 -0.1016)
			(stroke
				(width 0.1)
				(type default)
			)
			(layer "F.Fab")
		)
		(fp_line
			(start -0.2794 -0.1016)
			(end -0.2794 0.9906)
			(stroke
				(width 0.1)
				(type default)
			)
			(layer "F.Fab")
		)
		(fp_line
			(start 0.2794 0.9906)
			(end 0.2794 -0.1016)
			(stroke
				(width 0.1)
				(type default)
			)
			(layer "F.Fab")
		)
		(fp_line
			(start -0.2794 0.9906)
			(end 0.2794 0.9906)
			(stroke
				(width 0.1)
				(type default)
			)
			(layer "F.Fab")
		)
		(pad "1" smd rect
			(at 0 0 90)
			(size 0.508 0.508)
			(layers "F.Cu" "F.Mask" "F.Paste")
			(net "P3V3_STBY")
		)
		(pad "2" smd rect
			(at 0 0.889 90)
			(size 0.508 0.508)
			(layers "F.Cu" "F.Mask" "F.Paste")
			(net "PU_RST_PERST_BIT1")
		)
		(zone
			(layer "F.Cu")
			(hatch none 0.5)
			(connect_pads
				(clearance 0)
			)
			(min_thickness 0.25)
			(keepout
				(tracks allowed)
				(vias not_allowed)
				(pads allowed)
				(copperpour not_allowed)
				(footprints allowed)
			)
			(placement
				(enabled no)
				(sheetname "")
			)
			(fill
				(thermal_gap 0.5)
				(thermal_bridge_width 0.5)
				(island_removal_mode 0)
			)
			(polygon
				(pts
					(xy 370.365274 -63.859664) (xy 370.365274 -64.367664) (xy 370.746274 -64.367664) (xy 370.746274 -63.859664)
				)
			)
		)
		(zone
			(layer "F.Cu")
			(hatch none 0.5)
			(connect_pads
				(clearance 0)
			)
			(min_thickness 0.25)
			(keepout
				(tracks not_allowed)
				(vias allowed)
				(pads allowed)
				(copperpour not_allowed)
				(footprints allowed)
			)
			(placement
				(enabled no)
				(sheetname "")
			)
			(fill
				(thermal_gap 0.5)
				(thermal_bridge_width 0.5)
				(island_removal_mode 0)
			)
			(polygon
				(pts
					(xy 370.746274 -63.859664) (xy 370.746274 -64.367664) (xy 370.365274 -64.367664) (xy 370.365274 -63.859664)
				)
			)
		)
	)
	(footprint ""
		(layer "F.Cu")
		(at 172.0469 -6.9342 -90)
		(property "Reference" "R4G15"
			(at 0 0 270)
			(layer "F.SilkS")
			(hide yes)
			(effects
				(font
					(size 1.27 1.27)
				)
			)
		)
		(property "Value" ""
			(at 0 0 270)
			(layer "F.Fab")
			(effects
				(font
					(size 1.27 1.27)
				)
			)
		)
		(duplicate_pad_numbers_are_jumpers no)
		(fp_poly
			(pts
				(xy -0.2794 -0.1016) (xy 0.2794 -0.1016) (xy 0.2794 0.9906) (xy -0.2794 0.9906)
			)
			(stroke
				(width 0)
				(type default)
			)
			(fill no)
			(layer "F.CrtYd")
		)
		(fp_line
			(start -0.2794 0.9906)
			(end 0.2794 0.9906)
			(stroke
				(width 0.1)
				(type default)
			)
			(layer "F.Fab")
		)
		(fp_line
			(start 0.2794 0.9906)
			(end 0.2794 -0.1016)
			(stroke
				(width 0.1)
				(type default)
			)
			(layer "F.Fab")
		)
		(fp_line
			(start -0.2794 -0.1016)
			(end -0.2794 0.9906)
			(stroke
				(width 0.1)
				(type default)
			)
			(layer "F.Fab")
		)
		(fp_line
			(start 0.2794 -0.1016)
			(end -0.2794 -0.1016)
			(stroke
				(width 0.1)
				(type default)
			)
			(layer "F.Fab")
		)
		(pad "1" smd rect
			(at 0 0 270)
			(size 0.508 0.508)
			(layers "F.Cu" "F.Mask" "F.Paste")
			(net "PWRGD_PVTT_GHJ_CPU1_R")
		)
		(pad "2" smd rect
			(at 0 0.889 270)
			(size 0.508 0.508)
			(layers "F.Cu" "F.Mask" "F.Paste")
			(net "PWRGD_PVTT_CPU1")
		)
		(zone
			(layer "F.Cu")
			(hatch none 0.5)
			(connect_pads
				(clearance 0)
			)
			(min_thickness 0.25)
			(keepout
				(tracks not_allowed)
				(vias allowed)
				(pads allowed)
				(copperpour not_allowed)
				(footprints allowed)
			)
			(placement
				(enabled no)
				(sheetname "")
			)
			(fill
				(thermal_gap 0.5)
				(thermal_bridge_width 0.5)
				(island_removal_mode 0)
			)
			(polygon
				(pts
					(xy 171.4119 -7.1882) (xy 171.4119 -6.6802) (xy 171.7929 -6.6802) (xy 171.7929 -7.1882)
				)
			)
		)
		(zone
			(layer "F.Cu")
			(hatch none 0.5)
			(connect_pads
				(clearance 0)
			)
			(min_thickness 0.25)
			(keepout
				(tracks allowed)
				(vias not_allowed)
				(pads allowed)
				(copperpour not_allowed)
				(footprints allowed)
			)
			(placement
				(enabled no)
				(sheetname "")
			)
			(fill
				(thermal_gap 0.5)
				(thermal_bridge_width 0.5)
				(island_removal_mode 0)
			)
			(polygon
				(pts
					(xy 171.7929 -7.1882) (xy 171.7929 -6.6802) (xy 171.4119 -6.6802) (xy 171.4119 -7.1882)
				)
			)
		)
	)
	(footprint ""
		(layer "F.Cu")
		(at 402.641054 -43.729148 90)
		(property "Reference" "R1T35"
			(at 0 0 90)
			(layer "F.SilkS")
			(hide yes)
			(effects
				(font
					(size 1.27 1.27)
				)
			)
		)
		(property "Value" ""
			(at 0 0 90)
			(layer "F.Fab")
			(effects
				(font
					(size 1.27 1.27)
				)
			)
		)
		(duplicate_pad_numbers_are_jumpers no)
		(fp_poly
			(pts
				(xy -0.2794 -0.1016) (xy 0.2794 -0.1016) (xy 0.2794 0.9906) (xy -0.2794 0.9906)
			)
			(stroke
				(width 0)
				(type default)
			)
			(fill no)
			(layer "F.CrtYd")
		)
		(fp_line
			(start 0.2794 -0.1016)
			(end -0.2794 -0.1016)
			(stroke
				(width 0.1)
				(type default)
			)
			(layer "F.Fab")
		)
		(fp_line
			(start -0.2794 -0.1016)
			(end -0.2794 0.9906)
			(stroke
				(width 0.1)
				(type default)
			)
			(layer "F.Fab")
		)
		(fp_line
			(start 0.2794 0.9906)
			(end 0.2794 -0.1016)
			(stroke
				(width 0.1)
				(type default)
			)
			(layer "F.Fab")
		)
		(fp_line
			(start -0.2794 0.9906)
			(end 0.2794 0.9906)
			(stroke
				(width 0.1)
				(type default)
			)
			(layer "F.Fab")
		)
		(pad "1" smd rect
			(at 0 0 90)
			(size 0.508 0.508)
			(layers "F.Cu" "F.Mask" "F.Paste")
			(net "FM_CPU0_PROCHOT_LVT3_N")
		)
		(pad "2" smd rect
			(at 0 0.889 90)
			(size 0.508 0.508)
			(layers "F.Cu" "F.Mask" "F.Paste")
			(net "FM_CPU0_PROCHOT_PCH_N")
		)
		(zone
			(layer "F.Cu")
			(hatch none 0.5)
			(connect_pads
				(clearance 0)
			)
			(min_thickness 0.25)
			(keepout
				(tracks allowed)
				(vias not_allowed)
				(pads allowed)
				(copperpour not_allowed)
				(footprints allowed)
			)
			(placement
				(enabled no)
				(sheetname "")
			)
			(fill
				(thermal_gap 0.5)
				(thermal_bridge_width 0.5)
				(island_removal_mode 0)
			)
			(polygon
				(pts
					(xy 402.895054 -43.475148) (xy 402.895054 -43.983148) (xy 403.276054 -43.983148) (xy 403.276054 -43.475148)
				)
			)
		)
		(zone
			(layer "F.Cu")
			(hatch none 0.5)
			(connect_pads
				(clearance 0)
			)
			(min_thickness 0.25)
			(keepout
				(tracks not_allowed)
				(vias allowed)
				(pads allowed)
				(copperpour not_allowed)
				(footprints allowed)
			)
			(placement
				(enabled no)
				(sheetname "")
			)
			(fill
				(thermal_gap 0.5)
				(thermal_bridge_width 0.5)
				(island_removal_mode 0)
			)
			(polygon
				(pts
					(xy 403.276054 -43.475148) (xy 403.276054 -43.983148) (xy 402.895054 -43.983148) (xy 402.895054 -43.475148)
				)
			)
		)
	)
)
